# T6G (Grand Teton) — schematic netlist excerpt (pin names and nets, part order shuffled) for the footprints in the layout excerpt that follows; sources: Cadence DE-HDL packaged netlist, KiCad conversion of 04192023_DAF0TMB3IC0_F0TG_MB_C_brd_V02_OCP.brd

PR102  Q_RES  5.6 1% CHIP  pkg 0402LF  page 205 : A = SW_PVDDIO_P0_BOOT2 ; B = SW_PVDDIO_P0_BOOT2_R
C843  Q_CAP_DIFFBUS  DIFF BUS_0.22UF 6.3V 20% X6S  pkg C0201  page 64 : \1\ = P5E_CPU0_P2_TX_C_DP<13> ; \2\ = P5E_CPU0_P2_TX_DP<13>
PR510  Q_RES  1.5 1% EMPTY  pkg 0402LF  page 202 : A = SW_PVDDCR_CPU1_P0_SW3_RC ; B = GND

(kicad_pcb
	(version 20260206)
	(generator "pcbnew")
	(generator_version "10.0")
	(general
		(thickness 1.6)
		(legacy_teardrops no)
	)
	(paper "A4")
	(title_block
		(title "04192023_DAF0TMB3IC0_F0TG_MB_C_brd_V02_OCP.brd")
		(comment 1 "Grand Teton / footprints 3906-3908 of 8354")
	)
	(layers
		(0 "F.Cu" signal "TOP")
		(4 "In1.Cu" signal "GND")
		(6 "In2.Cu" signal "IN1")
		(8 "In3.Cu" signal "GND1")
		(10 "In4.Cu" signal "IN2")
		(12 "In5.Cu" signal "GND2")
		(14 "In6.Cu" signal "IN3")
		(16 "In7.Cu" signal "GND3")
		(18 "In8.Cu" signal "VCC")
		(20 "In9.Cu" signal "VCC1")
		(22 "In10.Cu" signal "GND4")
		(24 "In11.Cu" signal "IN4")
		(26 "In12.Cu" signal "GND5")
		(28 "In13.Cu" signal "IN5")
		(30 "In14.Cu" signal "GND6")
		(32 "In15.Cu" signal "IN6")
		(34 "In16.Cu" signal "GND7")
		(2 "B.Cu" signal "BOTTOM")
		(9 "F.Adhes" user "F.Adhesive")
		(11 "B.Adhes" user "B.Adhesive")
		(13 "F.Paste" user "Package Geometry/Pastemask Top")
		(15 "B.Paste" user "Package Geometry/Pastemask Bottom")
		(5 "F.SilkS" user "Ref Des/Silkscreen Top")
		(7 "B.SilkS" user "Ref Des/Silkscreen Bottom")
		(1 "F.Mask" user "Board Geometry/Soldermask Top")
		(3 "B.Mask" user "Board Geometry/Soldermask Bottom")
		(17 "Dwgs.User" user "User.Drawings")
		(19 "Cmts.User" user "User.Comments")
		(21 "Eco1.User" user "User.Eco1")
		(23 "Eco2.User" user "User.Eco2")
		(25 "Edge.Cuts" user "Board Geometry/Outline")
		(27 "Margin" user)
		(31 "F.CrtYd" user "Package Geometry/Place Bound Top")
		(29 "B.CrtYd" user "Package Geometry/Place Bound Bottom")
		(35 "F.Fab" user "Ref Des/Assembly Top")
		(33 "B.Fab" user "Ref Des/Assembly Bottom")
	)
	(footprint ""
		(layer "F.Cu")
		(at 314.668662 -333.260954 90)
		(property "Reference" "PR510"
			(at 0 0 90)
			(layer "F.SilkS")
			(hide yes)
			(effects
				(font
					(size 1.27 1.27)
				)
			)
		)
		(property "Value" ""
			(at 0 0 90)
			(layer "F.Fab")
			(effects
				(font
					(size 1.27 1.27)
				)
			)
		)
		(duplicate_pad_numbers_are_jumpers no)
		(fp_line
			(start 0.7874 -0.4064)
			(end 0.7874 0.4064)
			(stroke
				(width 0.1524)
				(type default)
			)
			(layer "F.SilkS")
		)
		(fp_line
			(start -0.7874 -0.4064)
			(end 0.7874 -0.4064)
			(stroke
				(width 0.1524)
				(type default)
			)
			(layer "F.SilkS")
		)
		(fp_line
			(start 0.7874 0.4064)
			(end -0.7874 0.4064)
			(stroke
				(width 0.1524)
				(type default)
			)
			(layer "F.SilkS")
		)
		(fp_line
			(start -0.7874 0.4064)
			(end -0.7874 -0.4064)
			(stroke
				(width 0.1524)
				(type default)
			)
			(layer "F.SilkS")
		)
		(fp_line
			(start -0.12065 -0.305054)
			(end -0.12065 -0.2794)
			(stroke
				(width 0.1)
				(type default)
			)
			(layer "F.Fab")
		)
		(fp_line
			(start -0.67945 -0.305054)
			(end -0.12065 -0.305054)
			(stroke
				(width 0.1)
				(type default)
			)
			(layer "F.Fab")
		)
		(fp_line
			(start 0.67945 -0.3048)
			(end 0.67945 0.3048)
			(stroke
				(width 0.1)
				(type default)
			)
			(layer "F.Fab")
		)
		(fp_line
			(start 0.12065 -0.3048)
			(end 0.67945 -0.3048)
			(stroke
				(width 0.1)
				(type default)
			)
			(layer "F.Fab")
		)
		(fp_line
			(start 0.12065 -0.2794)
			(end 0.12065 -0.3048)
			(stroke
				(width 0.1)
				(type default)
			)
			(layer "F.Fab")
		)
		(fp_line
			(start -0.12065 -0.2794)
			(end 0.12065 -0.2794)
			(stroke
				(width 0.1)
				(type default)
			)
			(layer "F.Fab")
		)
		(fp_line
			(start 0.120396 0.2794)
			(end -0.12065 0.2794)
			(stroke
				(width 0.1)
				(type default)
			)
			(layer "F.Fab")
		)
		(fp_line
			(start -0.12065 0.2794)
			(end -0.12065 0.3048)
			(stroke
				(width 0.1)
				(type default)
			)
			(layer "F.Fab")
		)
		(fp_line
			(start 0.67945 0.3048)
			(end 0.120396 0.3048)
			(stroke
				(width 0.1)
				(type default)
			)
			(layer "F.Fab")
		)
		(fp_line
			(start 0.120396 0.3048)
			(end 0.120396 0.2794)
			(stroke
				(width 0.1)
				(type default)
			)
			(layer "F.Fab")
		)
		(fp_line
			(start -0.12065 0.3048)
			(end -0.67945 0.3048)
			(stroke
				(width 0.1)
				(type default)
			)
			(layer "F.Fab")
		)
		(fp_line
			(start -0.67945 0.3048)
			(end -0.67945 -0.305054)
			(stroke
				(width 0.1)
				(type default)
			)
			(layer "F.Fab")
		)
		(pad "1" smd circle
			(at -0.40005 0 90)
			(size 0 0)
			(layers "F.Cu" "F.Mask" "F.Paste")
			(net "SW_PVDDCR_CPU1_P0_SW3_RC")
		)
		(pad "2" smd circle
			(at 0.40005 0 90)
			(size 0 0)
			(layers "F.Cu" "F.Mask" "F.Paste")
			(net "GND")
		)
	)
	(footprint ""
		(layer "F.Cu")
		(at 292.767512 -351.368106 90)
		(property "Reference" "PR102"
			(at 0 0 90)
			(layer "F.SilkS")
			(hide yes)
			(effects
				(font
					(size 1.27 1.27)
				)
			)
		)
		(property "Value" ""
			(at 0 0 90)
			(layer "F.Fab")
			(effects
				(font
					(size 1.27 1.27)
				)
			)
		)
		(duplicate_pad_numbers_are_jumpers no)
		(fp_line
			(start 0.7874 -0.4064)
			(end 0.7874 0.4064)
			(stroke
				(width 0.1524)
				(type default)
			)
			(layer "F.SilkS")
		)
		(fp_line
			(start -0.7874 -0.4064)
			(end 0.7874 -0.4064)
			(stroke
				(width 0.1524)
				(type default)
			)
			(layer "F.SilkS")
		)
		(fp_line
			(start 0.7874 0.4064)
			(end -0.7874 0.4064)
			(stroke
				(width 0.1524)
				(type default)
			)
			(layer "F.SilkS")
		)
		(fp_line
			(start -0.7874 0.4064)
			(end -0.7874 -0.4064)
			(stroke
				(width 0.1524)
				(type default)
			)
			(layer "F.SilkS")
		)
		(fp_line
			(start -0.12065 -0.305054)
			(end -0.12065 -0.2794)
			(stroke
				(width 0.1)
				(type default)
			)
			(layer "F.Fab")
		)
		(fp_line
			(start -0.67945 -0.305054)
			(end -0.12065 -0.305054)
			(stroke
				(width 0.1)
				(type default)
			)
			(layer "F.Fab")
		)
		(fp_line
			(start 0.67945 -0.3048)
			(end 0.67945 0.3048)
			(stroke
				(width 0.1)
				(type default)
			)
			(layer "F.Fab")
		)
		(fp_line
			(start 0.12065 -0.3048)
			(end 0.67945 -0.3048)
			(stroke
				(width 0.1)
				(type default)
			)
			(layer "F.Fab")
		)
		(fp_line
			(start 0.12065 -0.2794)
			(end 0.12065 -0.3048)
			(stroke
				(width 0.1)
				(type default)
			)
			(layer "F.Fab")
		)
		(fp_line
			(start -0.12065 -0.2794)
			(end 0.12065 -0.2794)
			(stroke
				(width 0.1)
				(type default)
			)
			(layer "F.Fab")
		)
		(fp_line
			(start 0.120396 0.2794)
			(end -0.12065 0.2794)
			(stroke
				(width 0.1)
				(type default)
			)
			(layer "F.Fab")
		)
		(fp_line
			(start -0.12065 0.2794)
			(end -0.12065 0.3048)
			(stroke
				(width 0.1)
				(type default)
			)
			(layer "F.Fab")
		)
		(fp_line
			(start 0.67945 0.3048)
			(end 0.120396 0.3048)
			(stroke
				(width 0.1)
				(type default)
			)
			(layer "F.Fab")
		)
		(fp_line
			(start 0.120396 0.3048)
			(end 0.120396 0.2794)
			(stroke
				(width 0.1)
				(type default)
			)
			(layer "F.Fab")
		)
		(fp_line
			(start -0.12065 0.3048)
			(end -0.67945 0.3048)
			(stroke
				(width 0.1)
				(type default)
			)
			(layer "F.Fab")
		)
		(fp_line
			(start -0.67945 0.3048)
			(end -0.67945 -0.305054)
			(stroke
				(width 0.1)
				(type default)
			)
			(layer "F.Fab")
		)
		(pad "1" smd circle
			(at -0.40005 0 90)
			(size 0 0)
			(layers "F.Cu" "F.Mask" "F.Paste")
			(net "SW_PVDDIO_P0_BOOT2")
		)
		(pad "2" smd circle
			(at 0.40005 0 90)
			(size 0 0)
			(layers "F.Cu" "F.Mask" "F.Paste")
			(net "SW_PVDDIO_P0_BOOT2_R")
		)
	)
	(footprint ""
		(layer "F.Cu")
		(at 424.14444 -378.95403 -90)
		(property "Reference" "C843"
			(at 0 0 270)
			(layer "F.SilkS")
			(hide yes)
			(effects
				(font
					(size 1.27 1.27)
				)
			)
		)
		(property "Value" ""
			(at 0 0 270)
			(layer "F.Fab")
			(effects
				(font
					(size 1.27 1.27)
				)
			)
		)
		(duplicate_pad_numbers_are_jumpers no)
		(fp_line
			(start -0.299974 0.150114)
			(end -0.299974 -0.150114)
			(stroke
				(width 0.1)
				(type default)
			)
			(layer "F.Fab")
		)
		(fp_line
			(start 0.299974 0.150114)
			(end -0.299974 0.150114)
			(stroke
				(width 0.1)
				(type default)
			)
			(layer "F.Fab")
		)
		(fp_line
			(start -0.299974 -0.150114)
			(end 0.299974 -0.150114)
			(stroke
				(width 0.1)
				(type default)
			)
			(layer "F.Fab")
		)
		(fp_line
			(start 0.299974 -0.150114)
			(end 0.299974 0.150114)
			(stroke
				(width 0.1)
				(type default)
			)
			(layer "F.Fab")
		)
		(pad "1" smd rect
			(at -0.2667 0 270)
			(size 0.3048 0.381)
			(layers "F.Cu" "F.Mask" "F.Paste")
			(net "P5E_CPU0_P2_TX_C_DP<13>")
		)
		(pad "2" smd rect
			(at 0.2667 0 270)
			(size 0.3048 0.381)
			(layers "F.Cu" "F.Mask" "F.Paste")
			(net "P5E_CPU0_P2_TX_DP<13>")
		)
	)
)
